(kicad_pcb
	(version 20260206)
	(generator "pcbnew")
	(generator_version "10.0")
	(general
		(thickness 1.6)
		(legacy_teardrops no)
	)
	(paper "A4")
	(title_block
		(title "01162023_DA0F0TEBIF0_F0T_Expander_BD_F_brd_V02_OCP.brd")
		(comment 1 "Grand Teton / footprint 6602 of 9728 (PEX1), pads 595-713 of 2397")
	)
	(layers
		(0 "F.Cu" signal "TOP")
		(4 "In1.Cu" signal "GND")
		(6 "In2.Cu" signal "VCC")
		(8 "In3.Cu" signal "VCC1")
		(10 "In4.Cu" signal "GND1")
		(12 "In5.Cu" signal "IN1")
		(14 "In6.Cu" signal "GND2")
		(16 "In7.Cu" signal "IN2")
		(18 "In8.Cu" signal "GND3")
		(20 "In9.Cu" signal "IN3")
		(22 "In10.Cu" signal "GND4")
		(24 "In11.Cu" signal "IN4")
		(26 "In12.Cu" signal "GND5")
		(28 "In13.Cu" signal "IN5")
		(30 "In14.Cu" signal "GND6")
		(32 "In15.Cu" signal "IN6")
		(34 "In16.Cu" signal "GND7")
		(2 "B.Cu" signal "BOTTOM")
		(9 "F.Adhes" user "F.Adhesive")
		(11 "B.Adhes" user "B.Adhesive")
		(13 "F.Paste" user "Package Geometry/Pastemask Top")
		(15 "B.Paste" user "Package Geometry/Pastemask Bottom")
		(5 "F.SilkS" user "Ref Des/Silkscreen Top")
		(7 "B.SilkS" user "Ref Des/Silkscreen Bottom")
		(1 "F.Mask" user "Board Geometry/Soldermask Top")
		(3 "B.Mask" user "Board Geometry/Soldermask Bottom")
		(17 "Dwgs.User" user "User.Drawings")
		(19 "Cmts.User" user "User.Comments")
		(21 "Eco1.User" user "User.Eco1")
		(23 "Eco2.User" user "User.Eco2")
		(25 "Edge.Cuts" user "Board Geometry/Outline")
		(27 "Margin" user)
		(31 "F.CrtYd" user "Package Geometry/Place Bound Top")
		(29 "B.CrtYd" user "Package Geometry/Place Bound Bottom")
		(35 "F.Fab" user "Ref Des/Assembly Top")
		(33 "B.Fab" user "Ref Des/Assembly Bottom")
	)
	(footprint ""
		(layer "F.Cu")
		(at 175.749966 -295.89984)
		(property "Reference" "PEX1"
			(at -3.353562 35.593274 0)
			(unlocked yes)
			(layer "F.SilkS")
			(effects
				(font
					(size 2.032 1.524)
					(thickness 0.1524)
				)
				(justify left)
			)
		)
		(property "Value" ""
			(at 0 0 0)
			(layer "F.Fab")
			(effects
				(font
					(size 1.27 1.27)
				)
			)
		)
		(duplicate_pad_numbers_are_jumpers no)
		(pad "AM9" smd circle
			(at -15.200122 6.649974)
			(size 0.4572 0.4572)
			(layers "F.Cu" "F.Mask" "F.Paste")
			(net "Net_1640")
		)
		(pad "AM10" smd circle
			(at -14.249908 6.649974)
			(size 0.4572 0.4572)
			(layers "F.Cu" "F.Mask" "F.Paste")
			(net "GND")
		)
		(pad "AM11" smd circle
			(at -13.299948 6.649974)
			(size 0.4572 0.4572)
			(layers "F.Cu" "F.Mask" "F.Paste")
			(net "GND")
		)
		(pad "AM12" smd circle
			(at -12.349988 6.649974)
			(size 0.4572 0.4572)
			(layers "F.Cu" "F.Mask" "F.Paste")
			(net "TP_PEX1_VDDQ_EFUSE")
		)
		(pad "AM13" smd circle
			(at -11.400028 6.649974)
			(size 0.4572 0.4572)
			(layers "F.Cu" "F.Mask" "F.Paste")
			(net "GND")
		)
		(pad "AM14" smd circle
			(at -10.450068 6.649974)
			(size 0.4572 0.4572)
			(layers "F.Cu" "F.Mask" "F.Paste")
			(net "P1V8_VDDA_PEX1")
		)
		(pad "AM15" smd circle
			(at -9.500108 6.649974)
			(size 0.4572 0.4572)
			(layers "F.Cu" "F.Mask" "F.Paste")
			(net "GND")
		)
		(pad "AM16" smd circle
			(at -8.549894 6.649974)
			(size 0.4572 0.4572)
			(layers "F.Cu" "F.Mask" "F.Paste")
			(net "P1V25_PEX1")
		)
		(pad "AM17" smd circle
			(at -7.599934 6.649974)
			(size 0.4572 0.4572)
			(layers "F.Cu" "F.Mask" "F.Paste")
			(net "P1V25_PEX1")
		)
		(pad "AM18" smd circle
			(at -6.649974 6.649974)
			(size 0.4572 0.4572)
			(layers "F.Cu" "F.Mask" "F.Paste")
			(net "P1V25_PEX1")
		)
		(pad "AM19" smd circle
			(at -5.700014 6.649974)
			(size 0.4572 0.4572)
			(layers "F.Cu" "F.Mask" "F.Paste")
			(net "P1V25_PEX1")
		)
		(pad "AM20" smd circle
			(at -4.750054 6.649974)
			(size 0.4572 0.4572)
			(layers "F.Cu" "F.Mask" "F.Paste")
			(net "P1V25_PEX1")
		)
		(pad "AM21" smd circle
			(at -3.800094 6.649974)
			(size 0.4572 0.4572)
			(layers "F.Cu" "F.Mask" "F.Paste")
			(net "P1V25_PEX1")
		)
		(pad "AM22" smd circle
			(at -2.84988 6.649974)
			(size 0.4572 0.4572)
			(layers "F.Cu" "F.Mask" "F.Paste")
			(net "P1V25_PEX1")
		)
		(pad "AM23" smd circle
			(at -1.89992 6.649974)
			(size 0.4572 0.4572)
			(layers "F.Cu" "F.Mask" "F.Paste")
			(net "P1V25_PEX1")
		)
		(pad "AM24" smd circle
			(at -0.94996 6.649974)
			(size 0.4572 0.4572)
			(layers "F.Cu" "F.Mask" "F.Paste")
			(net "P1V25_PEX1")
		)
		(pad "AM25" smd circle
			(at 0 6.649974)
			(size 0.4572 0.4572)
			(layers "F.Cu" "F.Mask" "F.Paste")
			(net "P1V25_PEX1")
		)
		(pad "AM26" smd circle
			(at 0.94996 6.649974)
			(size 0.4572 0.4572)
			(layers "F.Cu" "F.Mask" "F.Paste")
			(net "P1V25_PEX1")
		)
		(pad "AM27" smd circle
			(at 1.89992 6.649974)
			(size 0.4572 0.4572)
			(layers "F.Cu" "F.Mask" "F.Paste")
			(net "P1V25_PEX1")
		)
		(pad "AM28" smd circle
			(at 2.84988 6.649974)
			(size 0.4572 0.4572)
			(layers "F.Cu" "F.Mask" "F.Paste")
			(net "P1V25_PEX1")
		)
		(pad "AM29" smd circle
			(at 3.800094 6.649974)
			(size 0.4572 0.4572)
			(layers "F.Cu" "F.Mask" "F.Paste")
			(net "P1V25_PEX1")
		)
		(pad "AM30" smd circle
			(at 4.750054 6.649974)
			(size 0.4572 0.4572)
			(layers "F.Cu" "F.Mask" "F.Paste")
			(net "P1V25_PEX1")
		)
		(pad "AM31" smd circle
			(at 5.700014 6.649974)
			(size 0.4572 0.4572)
			(layers "F.Cu" "F.Mask" "F.Paste")
			(net "P1V25_PEX1")
		)
		(pad "AM32" smd circle
			(at 6.649974 6.649974)
			(size 0.4572 0.4572)
			(layers "F.Cu" "F.Mask" "F.Paste")
			(net "P1V25_PEX1")
		)
		(pad "AM33" smd circle
			(at 7.599934 6.649974)
			(size 0.4572 0.4572)
			(layers "F.Cu" "F.Mask" "F.Paste")
			(net "P1V25_PEX1")
		)
		(pad "AM34" smd circle
			(at 8.549894 6.649974)
			(size 0.4572 0.4572)
			(layers "F.Cu" "F.Mask" "F.Paste")
			(net "GND")
		)
		(pad "AM35" smd circle
			(at 9.500108 6.649974)
			(size 0.4572 0.4572)
			(layers "F.Cu" "F.Mask" "F.Paste")
			(net "P1V8_PEX")
		)
		(pad "AM36" smd circle
			(at 10.450068 6.649974)
			(size 0.4572 0.4572)
			(layers "F.Cu" "F.Mask" "F.Paste")
			(net "GND")
		)
		(pad "AM37" smd circle
			(at 11.400028 6.649974)
			(size 0.4572 0.4572)
			(layers "F.Cu" "F.Mask" "F.Paste")
			(net "GND")
		)
		(pad "AM38" smd circle
			(at 12.349988 6.649974)
			(size 0.4572 0.4572)
			(layers "F.Cu" "F.Mask" "F.Paste")
			(net "Net_5236")
		)
		(pad "AM39" smd circle
			(at 13.299948 6.649974)
			(size 0.4572 0.4572)
			(layers "F.Cu" "F.Mask" "F.Paste")
			(net "Net_5279")
		)
		(pad "AM40" smd circle
			(at 14.249908 6.649974)
			(size 0.4572 0.4572)
			(layers "F.Cu" "F.Mask" "F.Paste")
			(net "GND")
		)
		(pad "AM41" smd circle
			(at 15.200122 6.649974)
			(size 0.4572 0.4572)
			(layers "F.Cu" "F.Mask" "F.Paste")
			(net "Net_1406")
		)
		(pad "AM42" smd circle
			(at 16.150082 6.649974)
			(size 0.4572 0.4572)
			(layers "F.Cu" "F.Mask" "F.Paste")
			(net "Net_1429")
		)
		(pad "AM43" smd circle
			(at 17.100042 6.649974)
			(size 0.4572 0.4572)
			(layers "F.Cu" "F.Mask" "F.Paste")
			(net "GND")
		)
		(pad "AM44" smd circle
			(at 18.050002 6.649974)
			(size 0.4572 0.4572)
			(layers "F.Cu" "F.Mask" "F.Paste")
			(net "GND")
		)
		(pad "AM45" smd circle
			(at 18.999962 6.649974)
			(size 0.4572 0.4572)
			(layers "F.Cu" "F.Mask" "F.Paste")
			(net "GND")
		)
		(pad "AM46" smd circle
			(at 19.949922 6.649974)
			(size 0.4572 0.4572)
			(layers "F.Cu" "F.Mask" "F.Paste")
			(net "GND")
		)
		(pad "AM47" smd circle
			(at 20.899882 6.649974)
			(size 0.4572 0.4572)
			(layers "F.Cu" "F.Mask" "F.Paste")
			(net "GND")
		)
		(pad "AM48" smd circle
			(at 21.850096 6.649974)
			(size 0.4572 0.4572)
			(layers "F.Cu" "F.Mask" "F.Paste")
			(net "Net_1596")
		)
		(pad "AM49" smd circle
			(at 22.800056 6.649974)
			(size 0.4572 0.4572)
			(layers "F.Cu" "F.Mask" "F.Paste")
			(net "Net_1560")
		)
		(pad "AN1" smd circle
			(at -22.800056 7.599934)
			(size 0.4572 0.4572)
			(layers "F.Cu" "F.Mask" "F.Paste")
			(net "GND")
		)
		(pad "AN2" smd circle
			(at -21.850096 7.599934)
			(size 0.4572 0.4572)
			(layers "F.Cu" "F.Mask" "F.Paste")
			(net "GND")
		)
		(pad "AN3" smd circle
			(at -20.899882 7.599934)
			(size 0.4572 0.4572)
			(layers "F.Cu" "F.Mask" "F.Paste")
			(net "Net_1357")
		)
		(pad "AN4" smd circle
			(at -19.949922 7.599934)
			(size 0.4572 0.4572)
			(layers "F.Cu" "F.Mask" "F.Paste")
			(net "Net_1375")
		)
		(pad "AN5" smd circle
			(at -18.999962 7.599934)
			(size 0.4572 0.4572)
			(layers "F.Cu" "F.Mask" "F.Paste")
			(net "GND")
		)
		(pad "AN6" smd circle
			(at -18.050002 7.599934)
			(size 0.4572 0.4572)
			(layers "F.Cu" "F.Mask" "F.Paste")
			(net "Net_1654")
		)
		(pad "AN7" smd circle
			(at -17.100042 7.599934)
			(size 0.4572 0.4572)
			(layers "F.Cu" "F.Mask" "F.Paste")
			(net "Net_1652")
		)
		(pad "AN8" smd circle
			(at -16.150082 7.599934)
			(size 0.4572 0.4572)
			(layers "F.Cu" "F.Mask" "F.Paste")
			(net "GND")
		)
		(pad "AN9" smd circle
			(at -15.200122 7.599934)
			(size 0.4572 0.4572)
			(layers "F.Cu" "F.Mask" "F.Paste")
			(net "GND")
		)
		(pad "AN10" smd circle
			(at -14.249908 7.599934)
			(size 0.4572 0.4572)
			(layers "F.Cu" "F.Mask" "F.Paste")
			(net "GND")
		)
		(pad "AN11" smd circle
			(at -13.299948 7.599934)
			(size 0.4572 0.4572)
			(layers "F.Cu" "F.Mask" "F.Paste")
			(net "GND")
		)
		(pad "AN12" smd circle
			(at -12.349988 7.599934)
			(size 0.4572 0.4572)
			(layers "F.Cu" "F.Mask" "F.Paste")
			(net "GND")
		)
		(pad "AN13" smd circle
			(at -11.400028 7.599934)
			(size 0.4572 0.4572)
			(layers "F.Cu" "F.Mask" "F.Paste")
			(net "GND")
		)
		(pad "AN14" smd circle
			(at -10.450068 7.599934)
			(size 0.4572 0.4572)
			(layers "F.Cu" "F.Mask" "F.Paste")
			(net "Net_505")
		)
		(pad "AN15" smd circle
			(at -9.500108 7.599934)
			(size 0.4572 0.4572)
			(layers "F.Cu" "F.Mask" "F.Paste")
			(net "GND")
		)
		(pad "AN16" smd circle
			(at -8.549894 7.599934)
			(size 0.4572 0.4572)
			(layers "F.Cu" "F.Mask" "F.Paste")
			(net "GND")
		)
		(pad "AN17" smd circle
			(at -7.599934 7.599934)
			(size 0.4572 0.4572)
			(layers "F.Cu" "F.Mask" "F.Paste")
			(net "GND")
		)
		(pad "AN18" smd circle
			(at -6.649974 7.599934)
			(size 0.4572 0.4572)
			(layers "F.Cu" "F.Mask" "F.Paste")
			(net "GND")
		)
		(pad "AN19" smd circle
			(at -5.700014 7.599934)
			(size 0.4572 0.4572)
			(layers "F.Cu" "F.Mask" "F.Paste")
			(net "GND")
		)
		(pad "AN20" smd circle
			(at -4.750054 7.599934)
			(size 0.4572 0.4572)
			(layers "F.Cu" "F.Mask" "F.Paste")
			(net "GND")
		)
		(pad "AN21" smd circle
			(at -3.800094 7.599934)
			(size 0.4572 0.4572)
			(layers "F.Cu" "F.Mask" "F.Paste")
			(net "GND")
		)
		(pad "AN22" smd circle
			(at -2.84988 7.599934)
			(size 0.4572 0.4572)
			(layers "F.Cu" "F.Mask" "F.Paste")
			(net "GND")
		)
		(pad "AN23" smd circle
			(at -1.89992 7.599934)
			(size 0.4572 0.4572)
			(layers "F.Cu" "F.Mask" "F.Paste")
			(net "GND")
		)
		(pad "AN24" smd circle
			(at -0.94996 7.599934)
			(size 0.4572 0.4572)
			(layers "F.Cu" "F.Mask" "F.Paste")
			(net "GND")
		)
		(pad "AN25" smd circle
			(at 0 7.599934)
			(size 0.4572 0.4572)
			(layers "F.Cu" "F.Mask" "F.Paste")
			(net "GND")
		)
		(pad "AN26" smd circle
			(at 0.94996 7.599934)
			(size 0.4572 0.4572)
			(layers "F.Cu" "F.Mask" "F.Paste")
			(net "GND")
		)
		(pad "AN27" smd circle
			(at 1.89992 7.599934)
			(size 0.4572 0.4572)
			(layers "F.Cu" "F.Mask" "F.Paste")
			(net "GND")
		)
		(pad "AN28" smd circle
			(at 2.84988 7.599934)
			(size 0.4572 0.4572)
			(layers "F.Cu" "F.Mask" "F.Paste")
			(net "GND")
		)
		(pad "AN29" smd circle
			(at 3.800094 7.599934)
			(size 0.4572 0.4572)
			(layers "F.Cu" "F.Mask" "F.Paste")
			(net "GND")
		)
		(pad "AN30" smd circle
			(at 4.750054 7.599934)
			(size 0.4572 0.4572)
			(layers "F.Cu" "F.Mask" "F.Paste")
			(net "GND")
		)
		(pad "AN31" smd circle
			(at 5.700014 7.599934)
			(size 0.4572 0.4572)
			(layers "F.Cu" "F.Mask" "F.Paste")
			(net "GND")
		)
		(pad "AN32" smd circle
			(at 6.649974 7.599934)
			(size 0.4572 0.4572)
			(layers "F.Cu" "F.Mask" "F.Paste")
			(net "GND")
		)
		(pad "AN33" smd circle
			(at 7.599934 7.599934)
			(size 0.4572 0.4572)
			(layers "F.Cu" "F.Mask" "F.Paste")
			(net "GND")
		)
		(pad "AN34" smd circle
			(at 8.549894 7.599934)
			(size 0.4572 0.4572)
			(layers "F.Cu" "F.Mask" "F.Paste")
			(net "GND")
		)
		(pad "AN35" smd circle
			(at 9.500108 7.599934)
			(size 0.4572 0.4572)
			(layers "F.Cu" "F.Mask" "F.Paste")
			(net "GND")
		)
		(pad "AN36" smd circle
			(at 10.450068 7.599934)
			(size 0.4572 0.4572)
			(layers "F.Cu" "F.Mask" "F.Paste")
			(net "Net_507")
		)
		(pad "AN37" smd circle
			(at 11.400028 7.599934)
			(size 0.4572 0.4572)
			(layers "F.Cu" "F.Mask" "F.Paste")
			(net "GND")
		)
		(pad "AN38" smd circle
			(at 12.349988 7.599934)
			(size 0.4572 0.4572)
			(layers "F.Cu" "F.Mask" "F.Paste")
			(net "Net_5270")
		)
		(pad "AN39" smd circle
			(at 13.299948 7.599934)
			(size 0.4572 0.4572)
			(layers "F.Cu" "F.Mask" "F.Paste")
			(net "Net_5237")
		)
		(pad "AN40" smd circle
			(at 14.249908 7.599934)
			(size 0.4572 0.4572)
			(layers "F.Cu" "F.Mask" "F.Paste")
			(net "GND")
		)
		(pad "AN41" smd circle
			(at 15.200122 7.599934)
			(size 0.4572 0.4572)
			(layers "F.Cu" "F.Mask" "F.Paste")
			(net "GND")
		)
		(pad "AN42" smd circle
			(at 16.150082 7.599934)
			(size 0.4572 0.4572)
			(layers "F.Cu" "F.Mask" "F.Paste")
			(net "GND")
		)
		(pad "AN43" smd circle
			(at 17.100042 7.599934)
			(size 0.4572 0.4572)
			(layers "F.Cu" "F.Mask" "F.Paste")
			(net "P5E_PEX1_STN0_TX_DP<0>")
		)
		(pad "AN44" smd circle
			(at 18.050002 7.599934)
			(size 0.4572 0.4572)
			(layers "F.Cu" "F.Mask" "F.Paste")
			(net "P5E_PEX1_STN0_TX_DN<0>")
		)
		(pad "AN45" smd circle
			(at 18.999962 7.599934)
			(size 0.4572 0.4572)
			(layers "F.Cu" "F.Mask" "F.Paste")
			(net "GND")
		)
		(pad "AN46" smd circle
			(at 19.949922 7.599934)
			(size 0.4572 0.4572)
			(layers "F.Cu" "F.Mask" "F.Paste")
			(net "P5E_PEX1_STN0_RX_DP<0>")
		)
		(pad "AN47" smd circle
			(at 20.899882 7.599934)
			(size 0.4572 0.4572)
			(layers "F.Cu" "F.Mask" "F.Paste")
			(net "P5E_PEX1_STN0_RX_DN<0>")
		)
		(pad "AN48" smd circle
			(at 21.850096 7.599934)
			(size 0.4572 0.4572)
			(layers "F.Cu" "F.Mask" "F.Paste")
			(net "GND")
		)
		(pad "AN49" smd circle
			(at 22.800056 7.599934)
			(size 0.4572 0.4572)
			(layers "F.Cu" "F.Mask" "F.Paste")
			(net "GND")
		)
		(pad "AP1" smd circle
			(at -22.800056 8.549894)
			(size 0.4572 0.4572)
			(layers "F.Cu" "F.Mask" "F.Paste")
			(net "Net_1382")
		)
		(pad "AP2" smd circle
			(at -21.850096 8.549894)
			(size 0.4572 0.4572)
			(layers "F.Cu" "F.Mask" "F.Paste")
			(net "Net_1370")
		)
		(pad "AP3" smd circle
			(at -20.899882 8.549894)
			(size 0.4572 0.4572)
			(layers "F.Cu" "F.Mask" "F.Paste")
			(net "GND")
		)
		(pad "AP4" smd circle
			(at -19.949922 8.549894)
			(size 0.4572 0.4572)
			(layers "F.Cu" "F.Mask" "F.Paste")
			(net "GND")
		)
		(pad "AP5" smd circle
			(at -18.999962 8.549894)
			(size 0.4572 0.4572)
			(layers "F.Cu" "F.Mask" "F.Paste")
			(net "GND")
		)
		(pad "AP6" smd circle
			(at -18.050002 8.549894)
			(size 0.4572 0.4572)
			(layers "F.Cu" "F.Mask" "F.Paste")
			(net "GND")
		)
		(pad "AP7" smd circle
			(at -17.100042 8.549894)
			(size 0.4572 0.4572)
			(layers "F.Cu" "F.Mask" "F.Paste")
			(net "GND")
		)
		(pad "AP8" smd circle
			(at -16.150082 8.549894)
			(size 0.4572 0.4572)
			(layers "F.Cu" "F.Mask" "F.Paste")
			(net "Net_1638")
		)
		(pad "AP9" smd circle
			(at -15.200122 8.549894)
			(size 0.4572 0.4572)
			(layers "F.Cu" "F.Mask" "F.Paste")
			(net "Net_1670")
		)
		(pad "AP10" smd circle
			(at -14.249908 8.549894)
			(size 0.4572 0.4572)
			(layers "F.Cu" "F.Mask" "F.Paste")
			(net "GND")
		)
		(pad "AP11" smd circle
			(at -13.299948 8.549894)
			(size 0.4572 0.4572)
			(layers "F.Cu" "F.Mask" "F.Paste")
			(net "GND")
		)
		(pad "AP12" smd circle
			(at -12.349988 8.549894)
			(size 0.4572 0.4572)
			(layers "F.Cu" "F.Mask" "F.Paste")
			(net "GND")
		)
		(pad "AP13" smd circle
			(at -11.400028 8.549894)
			(size 0.4572 0.4572)
			(layers "F.Cu" "F.Mask" "F.Paste")
			(net "GND")
		)
		(pad "AP14" smd circle
			(at -10.450068 8.549894)
			(size 0.4572 0.4572)
			(layers "F.Cu" "F.Mask" "F.Paste")
			(net "Net_510")
		)
		(pad "AP15" smd circle
			(at -9.500108 8.549894)
			(size 0.4572 0.4572)
			(layers "F.Cu" "F.Mask" "F.Paste")
			(net "GND")
		)
		(pad "AP16" smd circle
			(at -8.549894 8.549894)
			(size 0.4572 0.4572)
			(layers "F.Cu" "F.Mask" "F.Paste")
			(net "P1V25_SERDES_VDDPLL_PEX1")
		)
		(pad "AP17" smd circle
			(at -7.599934 8.549894)
			(size 0.4572 0.4572)
			(layers "F.Cu" "F.Mask" "F.Paste")
			(net "P1V25_SERDES_VDDPLL_PEX1")
		)
		(pad "AP18" smd circle
			(at -6.649974 8.549894)
			(size 0.4572 0.4572)
			(layers "F.Cu" "F.Mask" "F.Paste")
			(net "P1V25_SERDES_VDDPLL_PEX1")
		)
		(pad "AP19" smd circle
			(at -5.700014 8.549894)
			(size 0.4572 0.4572)
			(layers "F.Cu" "F.Mask" "F.Paste")
			(net "P1V25_SERDES_VDDPLL_PEX1")
		)
		(pad "AP20" smd circle
			(at -4.750054 8.549894)
			(size 0.4572 0.4572)
			(layers "F.Cu" "F.Mask" "F.Paste")
			(net "P1V25_SERDES_VDDPLL_PEX1")
		)
		(pad "AP21" smd circle
			(at -3.800094 8.549894)
			(size 0.4572 0.4572)
			(layers "F.Cu" "F.Mask" "F.Paste")
			(net "P1V25_SERDES_VDDPLL_PEX1")
		)
		(pad "AP22" smd circle
			(at -2.84988 8.549894)
			(size 0.4572 0.4572)
			(layers "F.Cu" "F.Mask" "F.Paste")
			(net "P1V25_SERDES_VDDPLL_PEX1")
		)
		(pad "AP23" smd circle
			(at -1.89992 8.549894)
			(size 0.4572 0.4572)
			(layers "F.Cu" "F.Mask" "F.Paste")
			(net "P1V25_SERDES_VDDPLL_PEX1")
		)
		(pad "AP24" smd circle
			(at -0.94996 8.549894)
			(size 0.4572 0.4572)
			(layers "F.Cu" "F.Mask" "F.Paste")
			(net "P1V25_SERDES_VDDPLL_PEX1")
		)
		(pad "AP25" smd circle
			(at 0 8.549894)
			(size 0.4572 0.4572)
			(layers "F.Cu" "F.Mask" "F.Paste")
			(net "P1V25_SERDES_VDDPLL_PEX1")
		)
		(pad "AP26" smd circle
			(at 0.94996 8.549894)
			(size 0.4572 0.4572)
			(layers "F.Cu" "F.Mask" "F.Paste")
			(net "P1V25_SERDES_VDDPLL_PEX1")
		)
		(pad "AP27" smd circle
			(at 1.89992 8.549894)
			(size 0.4572 0.4572)
			(layers "F.Cu" "F.Mask" "F.Paste")
			(net "P1V25_SERDES_VDDPLL_PEX1")
		)
		(pad "AP28" smd circle
			(at 2.84988 8.549894)
			(size 0.4572 0.4572)
			(layers "F.Cu" "F.Mask" "F.Paste")
			(net "P1V25_SERDES_VDDPLL_PEX1")
		)
		(pad "AP29" smd circle
			(at 3.800094 8.549894)
			(size 0.4572 0.4572)
			(layers "F.Cu" "F.Mask" "F.Paste")
			(net "P1V25_SERDES_VDDPLL_PEX1")
		)
	)
)
